(kicad_pcb
	(version 20221018)
	(generator pcbnew)
	(general
    (thickness 1.518)
  )
	(paper "A4")
	(title_block
    (title "Kria K26 Devboard")
    (date "2024-03-26")
    (rev "1.2.5")
    (comment 1 "www.antmicro.com")
    (comment 2 "Antmicro Ltd.")
		(comment 9 "footprints 37-40 of 660")
	)
	(layers
    (0 "F.Cu" mixed)
    (1 "In1.Cu" power)
    (2 "In2.Cu" mixed)
    (3 "In3.Cu" power)
    (4 "In4.Cu" mixed)
    (5 "In5.Cu" power)
    (6 "In6.Cu" mixed)
    (31 "B.Cu" power)
    (32 "B.Adhes" user "B.Adhesive")
    (33 "F.Adhes" user "F.Adhesive")
    (34 "B.Paste" user)
    (35 "F.Paste" user)
    (36 "B.SilkS" user "B.Silkscreen")
    (37 "F.SilkS" user "F.Silkscreen")
    (38 "B.Mask" user)
    (39 "F.Mask" user)
    (40 "Dwgs.User" user "User.Drawings")
    (41 "Cmts.User" user "User.Comments")
    (42 "Eco1.User" user "User.Eco1")
    (43 "Eco2.User" user "User.Eco2")
    (44 "Edge.Cuts" user)
    (45 "Margin" user)
    (46 "B.CrtYd" user "B.Courtyard")
    (47 "F.CrtYd" user "F.Courtyard")
    (48 "B.Fab" user)
    (49 "F.Fab" user)
  )
	(footprint "kria-k26-devboard-footprints:USB-C_Receptacle_GCT_USB4105-GF-A" (layer "F.Cu")
    (at 146.699 55.855 180)
    (property "Author" "Antmicro")
    (property "License" "Apache-2.0")
    (property "MPN" "USB4105-GF-A")
    (property "Manufacturer" "GCT")
    (property "Sheetfile" "usbc-socket.kicad_sch")
    (property "Sheetname" "USB-C socket")
    (property "VSD_Class" "USB-C")
    (property "ki_description" "USB-C (USB TYPE-C) USB 2.0 Receptacle Connector 24 (16+8 Dummy) Position Surface Mount, Right Angle")
    (property "ki_keywords" "USB, CONNECTOR, SMT, HORIZONTAL")
    (attr smd)
    (fp_text reference "J10" (at 4.719 -5.015 180) (layer "F.SilkS")
        (effects (font (size 0.7 0.7) (thickness 0.15)) (justify left bottom))
    )
    (fp_text value "USB-C_GCT_USB4105-GF-A" (at 0 5 180) (layer "F.Fab") hide
        (effects (font (size 0.7 0.7) (thickness 0.15)) (justify left bottom))
    )
    (fp_text user "PCB-EDGE" (at -4.79 5.853 180) (layer "F.Fab") hide
        (effects (font (size 0.7 0.7) (thickness 0.15)) (justify left bottom))
    )
    (fp_text user "License: Apache-2.0" (at -4.79 8.855 180) (layer "F.Fab") hide
        (effects (font (size 0.7 0.7) (thickness 0.15)) (justify left bottom))
    )
    (fp_text user "${REFERENCE}" (at -4.79 6.853 180) (layer "F.Fab") hide
        (effects (font (size 0.7 0.7) (thickness 0.15)) (justify left bottom))
    )
    (fp_text user "Author: Antmicro" (at -4.79 7.853 180) (layer "F.Fab") hide
        (effects (font (size 0.7 0.7) (thickness 0.15)) (justify left bottom))
    )
    (fp_line (start -4.79 -1.395) (end -4.79 -0.145)
      (stroke (width 0.15) (type solid)) (layer "F.SilkS"))
    (fp_line (start -4.79 2.575) (end -4.79 3.854)
      (stroke (width 0.15) (type solid)) (layer "F.SilkS"))
    (fp_line (start -4.79 3.854) (end 4.788 3.854)
      (stroke (width 0.15) (type solid)) (layer "F.SilkS"))
    (fp_line (start 4.788 -1.395) (end 4.788 -0.145)
      (stroke (width 0.15) (type solid)) (layer "F.SilkS"))
    (fp_line (start 4.788 3.854) (end 4.788 2.575)
      (stroke (width 0.15) (type solid)) (layer "F.SilkS"))
    (fp_circle (center -3.8 -4.27071) (end -3.75 -4.22071)
      (stroke (width 0.15) (type solid)) (fill solid) (layer "F.SilkS"))
    (fp_rect (start -5.1 -4.4) (end 5.1 3.9)
      (stroke (width 0.05) (type solid)) (fill none) (layer "F.CrtYd"))
    (fp_line (start -4.79 -3.676) (end 4.788 -3.676)
      (stroke (width 0.15) (type solid)) (layer "F.Fab"))
    (fp_line (start -4.79 3.854) (end -4.79 -3.676)
      (stroke (width 0.15) (type solid)) (layer "F.Fab"))
    (fp_line (start -4.702 3.854) (end 4.788 3.854)
      (stroke (width 0.15) (type solid)) (layer "F.Fab"))
    (fp_line (start 4.788 -3.676) (end 4.788 3.854)
      (stroke (width 0.15) (type solid)) (layer "F.Fab"))
    (fp_line (start 4.788 3.854) (end -4.79 3.854)
      (stroke (width 0.15) (type solid)) (layer "F.Fab"))
    (pad "" np_thru_hole circle (at -2.891 -2.426 180) (size 0.65 0.65) (drill 0.65) (layers "*.Cu" "*.Mask"))
    (pad "" np_thru_hole circle (at 2.89 -2.426 180) (size 0.65 0.65) (drill 0.65) (layers "*.Cu" "*.Mask"))
    (pad "A1" smd roundrect (at -3.202 -3.5 180) (size 0.6 1.15) (layers "F.Cu" "F.Paste" "F.Mask") (roundrect_rratio 0.25)
      (net 1 "GND") (pinfunction "GND") (pintype "power_in"))
    (pad "A4" smd roundrect (at -2.4 -3.5 180) (size 0.6 1.15) (layers "F.Cu" "F.Paste" "F.Mask") (roundrect_rratio 0.25)
      (net 265 "/Debug and JTAG/USBC_VBUS") (pinfunction "VBUS") (pintype "passive"))
    (pad "A5" smd roundrect (at -1.25 -3.5 180) (size 0.3 1.15) (layers "F.Cu" "F.Paste" "F.Mask") (roundrect_rratio 0.25)
      (net 301 "/Power Supply/USB-C socket/USBC_TVS_CC1") (pinfunction "CC_{1}") (pintype "bidirectional"))
    (pad "A6" smd roundrect (at -0.25 -3.5 180) (size 0.3 1.15) (layers "F.Cu" "F.Paste" "F.Mask") (roundrect_rratio 0.25)
      (net 299 "/Power Supply/USB-C socket/USBC_TVS_P") (pinfunction "D_{A}+") (pintype "bidirectional"))
    (pad "A7" smd roundrect (at 0.248 -3.5 180) (size 0.3 1.15) (layers "F.Cu" "F.Paste" "F.Mask") (roundrect_rratio 0.25)
      (net 298 "/Power Supply/USB-C socket/USBC_TVS_N") (pinfunction "D_{A}-") (pintype "bidirectional"))
    (pad "A8" smd roundrect (at 1.249 -3.5 180) (size 0.3 1.15) (layers "F.Cu" "F.Paste" "F.Mask") (roundrect_rratio 0.25)
      (net 367 "unconnected-(J10-SBU_{1}-PadA8)") (pinfunction "SBU_{1}") (pintype "bidirectional+no_connect"))
    (pad "A9" smd roundrect (at 2.398 -3.5 180) (size 0.6 1.15) (layers "F.Cu" "F.Paste" "F.Mask") (roundrect_rratio 0.25)
      (net 265 "/Debug and JTAG/USBC_VBUS") (pinfunction "VBUS") (pintype "passive"))
    (pad "A12" smd roundrect (at 3.2 -3.5 180) (size 0.6 1.15) (layers "F.Cu" "F.Paste" "F.Mask") (roundrect_rratio 0.25)
      (net 1 "GND") (pinfunction "GND") (pintype "passive"))
    (pad "B1" smd roundrect (at 3.2 -3.5 180) (size 0.6 1.15) (layers "F.Cu" "F.Paste" "F.Mask") (roundrect_rratio 0.25)
      (net 1 "GND") (pinfunction "GND") (pintype "passive"))
    (pad "B4" smd roundrect (at 2.398 -3.5 180) (size 0.6 1.15) (layers "F.Cu" "F.Paste" "F.Mask") (roundrect_rratio 0.25)
      (net 265 "/Debug and JTAG/USBC_VBUS") (pinfunction "VBUS") (pintype "passive"))
    (pad "B5" smd roundrect (at 1.749 -3.5 180) (size 0.3 1.15) (layers "F.Cu" "F.Paste" "F.Mask") (roundrect_rratio 0.25)
      (net 300 "/Power Supply/USB-C socket/USBC_TVS_CC2") (pinfunction "CC_{2}") (pintype "bidirectional"))
    (pad "B6" smd roundrect (at 0.748 -3.5 180) (size 0.3 1.15) (layers "F.Cu" "F.Paste" "F.Mask") (roundrect_rratio 0.25)
      (net 299 "/Power Supply/USB-C socket/USBC_TVS_P") (pinfunction "D_{B}+") (pintype "bidirectional"))
    (pad "B7" smd roundrect (at -0.75 -3.5 180) (size 0.3 1.15) (layers "F.Cu" "F.Paste" "F.Mask") (roundrect_rratio 0.25)
      (net 298 "/Power Supply/USB-C socket/USBC_TVS_N") (pinfunction "D_{B}-") (pintype "bidirectional"))
    (pad "B8" smd roundrect (at -1.75 -3.5 180) (size 0.3 1.15) (layers "F.Cu" "F.Paste" "F.Mask") (roundrect_rratio 0.25)
      (net 368 "unconnected-(J10-SBU_{2}-PadB8)") (pinfunction "SBU_{2}") (pintype "bidirectional+no_connect"))
    (pad "B9" smd roundrect (at -2.4 -3.5 180) (size 0.6 1.15) (layers "F.Cu" "F.Paste" "F.Mask") (roundrect_rratio 0.25)
      (net 265 "/Debug and JTAG/USBC_VBUS") (pinfunction "VBUS") (pintype "passive"))
    (pad "B12" smd roundrect (at -3.202 -3.5 180) (size 0.6 1.15) (layers "F.Cu" "F.Paste" "F.Mask") (roundrect_rratio 0.25)
      (net 1 "GND") (pinfunction "GND") (pintype "passive"))
    (pad "SH" thru_hole oval (at -4.321 -2.926 180) (size 1.05 2.1) (drill oval 0.6 1.7) (layers "*.Cu" "*.Mask")
      (net 319 "SH_UP") (pinfunction "SH") (pintype "passive"))
    (pad "SH" thru_hole oval (at -4.321 1.255 180) (size 1 2) (drill oval 0.6 1.4) (layers "*.Cu" "*.Mask")
      (net 319 "SH_UP") (pinfunction "SH") (pintype "passive"))
    (pad "SH" thru_hole oval (at 4.32 -2.926 180) (size 1.05 2.1) (drill oval 0.6 1.7) (layers "*.Cu" "*.Mask")
      (net 319 "SH_UP") (pinfunction "SH") (pintype "passive"))
    (pad "SH" thru_hole oval (at 4.32 1.255 180) (size 1 2) (drill oval 0.6 1.4) (layers "*.Cu" "*.Mask")
      (net 319 "SH_UP") (pinfunction "SH") (pintype "passive"))
  )
	(footprint "kria-k26-devboard-footprints:R_0402_1005Metric" (layer "F.Cu")
    (at 151.9 65.5 -90)
    (descr "Resistor SMD 0402")
    (tags "resistor SMD 0402")
    (property "Author" "Antmicro")
    (property "License" "Apache-2.0")
    (property "MPN" "CR0402-FX-1003GLF")
    (property "Manufacturer" "Bourns")
    (property "Sheetfile" "usbc-socket.kicad_sch")
    (property "Sheetname" "USB-C socket")
    (property "Tolerance" "1%")
    (property "Val" "100k")
    (property "ki_description" "100k resistor in 0402 package with 1% tolerance")
    (attr smd)
    (fp_text reference "R149" (at 0.38 -1.23 -90) (layer "F.SilkS")
        (effects (font (size 0.7 0.7) (thickness 0.15)) (justify left bottom))
    )
    (fp_text value "R_100k_0402" (at 0 1.4 -90) (layer "F.Fab") hide
        (effects (font (size 0.7 0.7) (thickness 0.15)) (justify left bottom))
    )
    (fp_text user "License: Apache-2.0" (at -0.95 5.169 -90) (layer "F.Fab") hide
        (effects (font (size 0.7 0.7) (thickness 0.15)) (justify left bottom))
    )
    (fp_text user "Author: Antmicro" (at -0.95 4.169 -90) (layer "F.Fab") hide
        (effects (font (size 0.7 0.7) (thickness 0.15)) (justify left bottom))
    )
    (fp_text user "${REFERENCE}" (at -0.95 3.168 -90) (layer "F.Fab") hide
        (effects (font (size 0.7 0.7) (thickness 0.15)) (justify left bottom))
    )
    (fp_rect (start -0.93 -0.47) (end 0.93 0.47)
      (stroke (width 0.05) (type solid)) (fill none) (layer "F.CrtYd"))
    (fp_rect (start -0.5 -0.25) (end 0.5 0.25)
      (stroke (width 0.15) (type solid)) (fill none) (layer "F.Fab"))
    (pad "1" smd roundrect (at -0.485 0 270) (size 0.59 0.64) (layers "F.Cu" "F.Paste" "F.Mask") (roundrect_rratio 0.25)
      (net 265 "/Debug and JTAG/USBC_VBUS") (pintype "passive"))
    (pad "2" smd roundrect (at 0.485 0 270) (size 0.59 0.64) (layers "F.Cu" "F.Paste" "F.Mask") (roundrect_rratio 0.25)
      (net 433 "Net-(Q16-G)") (pintype "passive"))
  )
	(footprint "kria-k26-devboard-footprints:C_0402_1005Metric" (layer "F.Cu")
    (at 186.775 61.75)
    (descr "Capacitor SMD 0402")
    (tags "capacitor SMD 0402")
    (property "Author" "Antmicro")
    (property "Dielectric" "")
    (property "License" "Apache-2.0")
    (property "MPN" "GRM155R71H104KE14D")
    (property "Manufacturer" "Murata")
    (property "Sheetfile" "dc-input.kicad_sch")
    (property "Sheetname" "DC Input")
    (property "Val" "100n/50V")
    (property "Voltage" "")
    (property "ki_description" " ")
    (attr smd)
    (fp_text reference "C232" (at 0.955 0.36) (layer "F.SilkS")
        (effects (font (size 0.7 0.7) (thickness 0.15)) (justify left bottom))
    )
    (fp_text value "C_100n_50V_0402" (at 0 1.4) (layer "F.Fab") hide
        (effects (font (size 0.7 0.7) (thickness 0.15)) (justify left bottom))
    )
    (fp_text user "${REFERENCE}" (at -0.932 3.168) (layer "F.Fab") hide
        (effects (font (size 0.7 0.7) (thickness 0.15)) (justify left bottom))
    )
    (fp_text user "License: Apache-2.0" (at -0.932 5.17) (layer "F.Fab") hide
        (effects (font (size 0.7 0.7) (thickness 0.15)) (justify left bottom))
    )
    (fp_text user "Author: Antmicro" (at -0.932 4.17) (layer "F.Fab") hide
        (effects (font (size 0.7 0.7) (thickness 0.15)) (justify left bottom))
    )
    (fp_rect (start -0.94 -0.47) (end 0.94 0.47)
      (stroke (width 0.05) (type solid)) (fill none) (layer "F.CrtYd"))
    (fp_rect (start -0.499 -0.249) (end 0.499 0.249)
      (stroke (width 0.15) (type solid)) (fill none) (layer "F.Fab"))
    (pad "1" smd roundrect (at -0.484 0) (size 0.59 0.64) (layers "F.Cu" "F.Paste" "F.Mask") (roundrect_rratio 0.25)
      (net 22 "/Power Supply/DC Input/DC_IN") (pintype "passive"))
    (pad "2" smd roundrect (at 0.484 0) (size 0.59 0.64) (layers "F.Cu" "F.Paste" "F.Mask") (roundrect_rratio 0.25)
      (net 1 "GND") (pintype "passive"))
  )
	(footprint "kria-k26-devboard-footprints:BarrelJack_Pin2mm_MJ-179PH" (layer "F.Cu")
    (at 180 65.695 90)
    (property "Author" "Antmicro")
    (property "License" "Apache-2.0")
    (property "MPN" "MJ-179PH")
    (property "Manufacturer" "Multicomp Pro")
    (property "Sheetfile" "dc-input.kicad_sch")
    (property "Sheetname" "DC Input")
    (property "ki_description" "DC Power Connector, Jack, 4 A, 1.95 mm, PCB Mount, Through Hole")
    (property "ki_keywords" "HORIZONTAL, THT, JACK, CONNECTOR, POWER")
    (attr through_hole)
    (fp_text reference "J11" (at 11.715 -5.04 90) (layer "F.SilkS")
        (effects (font (size 0.7 0.7) (thickness 0.15)) (justify left bottom))
    )
    (fp_text value "BarrelJack_Pin2mm_MJ-179PH" (at 0 15.4 90) (layer "F.Fab") hide
        (effects (font (size 0.7 0.7) (thickness 0.15)) (justify left bottom))
    )
    (fp_text user "${REFERENCE}" (at -5.1 16.4 90) (layer "F.Fab") hide
        (effects (font (size 0.7 0.7) (thickness 0.15)) (justify left bottom))
    )
    (fp_text user "Author: Antmicro" (at -5.1 17.601 90) (layer "F.Fab") hide
        (effects (font (size 0.7 0.7) (thickness 0.15)) (justify left bottom))
    )
    (fp_text user "License: Apache-2.0" (at -5.1 18.802 90) (layer "F.Fab") hide
        (effects (font (size 0.7 0.7) (thickness 0.15)) (justify left bottom))
    )
    (fp_line (start -0.1 -4.8) (end 0.8255 -4.8)
      (stroke (width 0.15) (type solid)) (layer "F.SilkS"))
    (fp_line (start -0.1 -2.4) (end -0.1 -4.8)
      (stroke (width 0.15) (type solid)) (layer "F.SilkS"))
    (fp_line (start -0.1 4.8) (end -0.1 2.4)
      (stroke (width 0.15) (type solid)) (layer "F.SilkS"))
    (fp_line (start 10.1 4.8) (end 10.1 -4.8)
      (stroke (width 0.15) (type solid)) (layer "F.SilkS"))
    (fp_line (start 14 -4.8) (end 5.1 -4.8)
      (stroke (width 0.15) (type solid)) (layer "F.SilkS"))
    (fp_line (start 14 4.8) (end -0.1 4.8)
      (stroke (width 0.15) (type solid)) (layer "F.SilkS"))
    (fp_line (start 14 4.8) (end 14 -4.8)
      (stroke (width 0.15) (type solid)) (layer "F.SilkS"))
    (fp_line (start -1.3 -2.5) (end -1.3 2.5)
      (stroke (width 0.05) (type solid)) (layer "F.CrtYd"))
    (fp_line (start -1.3 2.5) (end -0.4 2.5)
      (stroke (width 0.05) (type solid)) (layer "F.CrtYd"))
    (fp_line (start -0.4 -5.1) (end -0.4 -2.5)
      (stroke (width 0.05) (type solid)) (layer "F.CrtYd"))
    (fp_line (start -0.4 -2.5) (end -1.3 -2.5)
      (stroke (width 0.05) (type solid)) (layer "F.CrtYd"))
    (fp_line (start -0.4 2.5) (end -0.4 5.1)
      (stroke (width 0.05) (type solid)) (layer "F.CrtYd"))
    (fp_line (start -0.4 5.1) (end 14.3 5.1)
      (stroke (width 0.05) (type solid)) (layer "F.CrtYd"))
    (fp_line (start 0.7 -6.1) (end 0.7 -5.1)
      (stroke (width 0.05) (type solid)) (layer "F.CrtYd"))
    (fp_line (start 0.7 -5.1) (end -0.4 -5.1)
      (stroke (width 0.05) (type solid)) (layer "F.CrtYd"))
    (fp_line (start 5.2 -6.1) (end 0.7 -6.1)
      (stroke (width 0.05) (type solid)) (layer "F.CrtYd"))
    (fp_line (start 5.2 -5.1) (end 5.2 -6.1)
      (stroke (width 0.05) (type solid)) (layer "F.CrtYd"))
    (fp_line (start 14.3 -5.1) (end 5.2 -5.1)
      (stroke (width 0.05) (type solid)) (layer "F.CrtYd"))
    (fp_line (start 14.3 5.1) (end 14.3 -5.1)
      (stroke (width 0.05) (type solid)) (layer "F.CrtYd"))
    (fp_line (start -0.4 3.6) (end 0.5 4.5)
      (stroke (width 0.15) (type solid)) (layer "F.Fab"))
    (fp_rect (start -0.4 4.5) (end 13.7 -5.111)
      (stroke (width 0.15) (type solid)) (fill none) (layer "F.Fab"))
    (pad "1" thru_hole oval (at 0 0 90) (size 2 4.5) (drill oval 1 3.5) (layers "*.Cu" "*.Mask")
      (net 22 "/Power Supply/DC Input/DC_IN") (pinfunction "1") (pintype "passive"))
    (pad "2" thru_hole oval (at 2.948 -4.879) (size 1.99 4) (drill oval 1 3) (layers "*.Cu" "*.Mask")
      (net 437 "unconnected-(J11-Pad2)") (pinfunction "2") (pintype "passive+no_connect"))
    (pad "3" thru_hole oval (at 5.999 0 270) (size 2 4) (drill oval 1 3) (layers "*.Cu" "*.Mask")
      (net 1 "GND") (pinfunction "3") (pintype "passive"))
  )
)
